#ISCELL
  pure_quanta quanta_title_block_c *
  *
#CELL
  pure_quanta socket4677_azif0045p001c01cs *
  page68_i1
#ISCELL
  logical_power vcc_core *
  page68_i10
#ISCELL
  logical_power vcc_core *
  page68_i11
#ISCELL
  logical_power vcc_core *
  page68_i12
#ISCELL
  logical_power vcc_core *
  page68_i13
#ISCELL
  logical_power vcc_core *
  page68_i2
#ISCELL
  logical_power vcc_core *
  page68_i3
#CELL
  pure_quanta q_cap *
  page68_i4
#ISCELL
  logical_power universal_gnd *
  page68_i5
#ISCELL
  logical_power vcc_core *
  page68_i6
#ISCELL
  logical_power vcc_core *
  page68_i7
#CELL
  pure_quanta socket4677_azif0045p001c01cs *
  page68_i8
#ISCELL
  logical_power vcc_core *
  page68_i9
